(kicad_pcb
	(version 20260206)
	(generator "pcbnew")
	(generator_version "10.0")
	(general
		(thickness 1.6)
		(legacy_teardrops no)
	)
	(paper "A4")
	(title_block
		(title "Bryce Canyon_IOM_IOC_16318-2_OCP.brd")
		(comment 1 "Bryce Canyon / footprints 1090-1099 of 1605")
	)
	(layers
		(0 "F.Cu" signal "TOP")
		(4 "In1.Cu" signal "L2GND")
		(6 "In2.Cu" signal "L3")
		(8 "In3.Cu" signal "L4VCC")
		(10 "In4.Cu" signal "L5VCC")
		(12 "In5.Cu" signal "L6")
		(14 "In6.Cu" signal "L7GND")
		(2 "B.Cu" signal "BOTTOM")
		(9 "F.Adhes" user "F.Adhesive")
		(11 "B.Adhes" user "B.Adhesive")
		(13 "F.Paste" user "Package Geometry/Pastemask Top")
		(15 "B.Paste" user "Package Geometry/Pastemask Bottom")
		(5 "F.SilkS" user "Ref Des/Silkscreen Top")
		(7 "B.SilkS" user "Ref Des/Silkscreen Bottom")
		(1 "F.Mask" user "Board Geometry/Soldermask Top")
		(3 "B.Mask" user "Board Geometry/Soldermask Bottom")
		(17 "Dwgs.User" user "User.Drawings")
		(19 "Cmts.User" user "User.Comments")
		(21 "Eco1.User" user "User.Eco1")
		(23 "Eco2.User" user "User.Eco2")
		(25 "Edge.Cuts" user "Board Geometry/Outline")
		(27 "Margin" user)
		(31 "F.CrtYd" user "Package Geometry/Place Bound Top")
		(29 "B.CrtYd" user "Package Geometry/Place Bound Bottom")
		(35 "F.Fab" user "Ref Des/Assembly Top")
		(33 "B.Fab" user "Ref Des/Assembly Bottom")
	)
	(footprint ""
		(layer "B.Cu")
		(at 183.01462 -79.30134)
		(property "Reference" "TP85"
			(at 0 0 0)
			(layer "B.SilkS")
			(hide yes)
			(effects
				(font
					(size 1.27 1.27)
				)
				(justify mirror)
			)
		)
		(property "Value" "TPAD28-2-GP"
			(at 0.0127 -1.6637 0)
			(unlocked yes)
			(layer "B.Fab")
			(hide yes)
			(effects
				(font
					(size 1.016 1.016)
					(thickness 0.1524)
				)
				(justify mirror)
			)
		)
		(property "Device Type" "TPAD28"
			(at 0.0127 -3.1877 0)
			(unlocked yes)
			(layer "B.Fab")
			(hide yes)
			(effects
				(font
					(size 1.016 1.016)
					(thickness 0.1524)
				)
				(justify mirror)
			)
		)
		(duplicate_pad_numbers_are_jumpers no)
		(fp_poly
			(pts
				(arc
					(start 0.3556 0)
					(mid -0.3556 0)
					(end 0.3556 0)
				)
			)
			(stroke
				(width 0)
				(type default)
			)
			(fill no)
			(layer "B.CrtYd")
		)
		(fp_poly
			(pts
				(arc
					(start 0.6096 0)
					(mid -0.6096 0)
					(end 0.6096 0)
				)
			)
			(stroke
				(width 0)
				(type default)
			)
			(fill no)
			(layer "B.Fab")
		)
		(pad "1" smd circle
			(at 0 0 180)
			(size 0.7112 0.7112)
			(layers "B.Cu" "B.Mask" "B.Paste")
			(net "IOC_GPIO_1")
		)
	)
	(footprint ""
		(layer "B.Cu")
		(at 124.839476 -8.75157 90)
		(property "Reference" "R449"
			(at 0 0 90)
			(layer "B.SilkS")
			(hide yes)
			(effects
				(font
					(size 1.27 1.27)
				)
				(justify mirror)
			)
		)
		(property "Value" "1KR2J-1-GP"
			(at -0.064008 -3.993896 90)
			(unlocked yes)
			(layer "B.Fab")
			(hide yes)
			(effects
				(font
					(size 1.016 1.016)
					(thickness 0.1524)
				)
				(justify mirror)
			)
		)
		(property "Device Type" "R402H16"
			(at -0.064008 -5.517896 90)
			(unlocked yes)
			(layer "B.Fab")
			(hide yes)
			(effects
				(font
					(size 1.016 1.016)
					(thickness 0.1524)
				)
				(justify mirror)
			)
		)
		(duplicate_pad_numbers_are_jumpers no)
		(fp_line
			(start 0.508 -0.9398)
			(end 0.508 0.9398)
			(stroke
				(width 0.1524)
				(type default)
			)
			(layer "B.SilkS")
		)
		(fp_line
			(start -0.508 -0.9398)
			(end 0.508 -0.9398)
			(stroke
				(width 0.1524)
				(type default)
			)
			(layer "B.SilkS")
		)
		(fp_rect
			(start 0.508 0.9398)
			(end -0.508 -0.9398)
			(stroke
				(width 0)
				(type default)
			)
			(fill no)
			(layer "B.CrtYd")
		)
		(fp_rect
			(start 0.508 0.9398)
			(end -0.508 -0.9398)
			(stroke
				(width 0)
				(type default)
			)
			(fill no)
			(layer "B.Fab")
		)
		(pad "1" smd custom
			(at 0 -0.4445 270)
			(size 0.1397 0.1397)
			(layers "B.Cu" "B.Mask" "B.Paste")
			(net "MB0_CM_VOUT_R")
			(options
				(clearance outline)
				(anchor circle)
			)
			(primitives
				(gr_poly
					(pts
						(arc
							(start -0.1778 0.2794)
							(mid -0.249642 0.249642)
							(end -0.2794 0.1778)
						)
						(arc
							(start -0.2794 -0.1778)
							(mid -0.249642 -0.249642)
							(end -0.1778 -0.2794)
						)
						(arc
							(start 0.1778 -0.2794)
							(mid 0.249642 -0.249642)
							(end 0.2794 -0.1778)
						)
						(arc
							(start 0.2794 0.1778)
							(mid 0.249642 0.249642)
							(end 0.1778 0.2794)
						)
					)
					(width 0)
					(fill yes)
				)
			)
		)
		(pad "2" smd custom
			(at 0 0.4445 270)
			(size 0.1397 0.1397)
			(layers "B.Cu" "B.Mask" "B.Paste")
			(net "P12V_STBY")
			(options
				(clearance outline)
				(anchor circle)
			)
			(primitives
				(gr_poly
					(pts
						(arc
							(start -0.1778 0.2794)
							(mid -0.249642 0.249642)
							(end -0.2794 0.1778)
						)
						(arc
							(start -0.2794 -0.1778)
							(mid -0.249642 -0.249642)
							(end -0.1778 -0.2794)
						)
						(arc
							(start 0.1778 -0.2794)
							(mid 0.249642 -0.249642)
							(end 0.2794 -0.1778)
						)
						(arc
							(start 0.2794 0.1778)
							(mid 0.249642 0.249642)
							(end 0.1778 0.2794)
						)
					)
					(width 0)
					(fill yes)
				)
			)
		)
	)
	(footprint ""
		(layer "B.Cu")
		(at 187.185808 -79.093314)
		(property "Reference" "TP91"
			(at 0 0 0)
			(layer "B.SilkS")
			(hide yes)
			(effects
				(font
					(size 1.27 1.27)
				)
				(justify mirror)
			)
		)
		(property "Value" "TPAD28-2-GP"
			(at 0.0127 -1.6637 0)
			(unlocked yes)
			(layer "B.Fab")
			(hide yes)
			(effects
				(font
					(size 1.016 1.016)
					(thickness 0.1524)
				)
				(justify mirror)
			)
		)
		(property "Device Type" "TPAD28"
			(at 0.0127 -3.1877 0)
			(unlocked yes)
			(layer "B.Fab")
			(hide yes)
			(effects
				(font
					(size 1.016 1.016)
					(thickness 0.1524)
				)
				(justify mirror)
			)
		)
		(duplicate_pad_numbers_are_jumpers no)
		(fp_poly
			(pts
				(arc
					(start 0.3556 0)
					(mid -0.3556 0)
					(end 0.3556 0)
				)
			)
			(stroke
				(width 0)
				(type default)
			)
			(fill no)
			(layer "B.CrtYd")
		)
		(fp_poly
			(pts
				(arc
					(start 0.6096 0)
					(mid -0.6096 0)
					(end 0.6096 0)
				)
			)
			(stroke
				(width 0)
				(type default)
			)
			(fill no)
			(layer "B.Fab")
		)
		(pad "1" smd circle
			(at 0 0 180)
			(size 0.7112 0.7112)
			(layers "B.Cu" "B.Mask" "B.Paste")
			(net "IOC_GPIO_6")
		)
	)
	(footprint ""
		(layer "B.Cu")
		(at 48.514 -135.7122)
		(property "Reference" "R142"
			(at 0 0 0)
			(layer "B.SilkS")
			(hide yes)
			(effects
				(font
					(size 1.27 1.27)
				)
				(justify mirror)
			)
		)
		(property "Value" "200R2F-L-GP"
			(at -0.064008 -3.993896 0)
			(unlocked yes)
			(layer "B.Fab")
			(hide yes)
			(effects
				(font
					(size 1.016 1.016)
					(thickness 0.1524)
				)
				(justify mirror)
			)
		)
		(property "Device Type" "R402H16"
			(at -0.064008 -5.517896 0)
			(unlocked yes)
			(layer "B.Fab")
			(hide yes)
			(effects
				(font
					(size 1.016 1.016)
					(thickness 0.1524)
				)
				(justify mirror)
			)
		)
		(duplicate_pad_numbers_are_jumpers no)
		(fp_line
			(start -0.508 -0.9398)
			(end 0.508 -0.9398)
			(stroke
				(width 0.1524)
				(type default)
			)
			(layer "B.SilkS")
		)
		(fp_line
			(start 0.508 -0.9398)
			(end 0.508 0.9398)
			(stroke
				(width 0.1524)
				(type default)
			)
			(layer "B.SilkS")
		)
		(fp_rect
			(start 0.508 0.9398)
			(end -0.508 -0.9398)
			(stroke
				(width 0)
				(type default)
			)
			(fill no)
			(layer "B.CrtYd")
		)
		(fp_rect
			(start 0.508 0.9398)
			(end -0.508 -0.9398)
			(stroke
				(width 0)
				(type default)
			)
			(fill no)
			(layer "B.Fab")
		)
		(pad "1" smd custom
			(at 0 -0.4445 180)
			(size 0.1397 0.1397)
			(layers "B.Cu" "B.Mask" "B.Paste")
			(net "BMC_PEREXT")
			(options
				(clearance outline)
				(anchor circle)
			)
			(primitives
				(gr_poly
					(pts
						(arc
							(start -0.1778 0.2794)
							(mid -0.249642 0.249642)
							(end -0.2794 0.1778)
						)
						(arc
							(start -0.2794 -0.1778)
							(mid -0.249642 -0.249642)
							(end -0.1778 -0.2794)
						)
						(arc
							(start 0.1778 -0.2794)
							(mid 0.249642 -0.249642)
							(end 0.2794 -0.1778)
						)
						(arc
							(start 0.2794 0.1778)
							(mid 0.249642 0.249642)
							(end 0.1778 0.2794)
						)
					)
					(width 0)
					(fill yes)
				)
			)
		)
		(pad "2" smd custom
			(at 0 0.4445 180)
			(size 0.1397 0.1397)
			(layers "B.Cu" "B.Mask" "B.Paste")
			(net "GND")
			(options
				(clearance outline)
				(anchor circle)
			)
			(primitives
				(gr_poly
					(pts
						(arc
							(start -0.1778 0.2794)
							(mid -0.249642 0.249642)
							(end -0.2794 0.1778)
						)
						(arc
							(start -0.2794 -0.1778)
							(mid -0.249642 -0.249642)
							(end -0.1778 -0.2794)
						)
						(arc
							(start 0.1778 -0.2794)
							(mid 0.249642 -0.249642)
							(end 0.2794 -0.1778)
						)
						(arc
							(start 0.2794 0.1778)
							(mid 0.249642 0.249642)
							(end 0.1778 0.2794)
						)
					)
					(width 0)
					(fill yes)
				)
			)
		)
	)
	(footprint ""
		(layer "B.Cu")
		(at 57.386728 -139.262104)
		(property "Reference" "TP76"
			(at 0 0 0)
			(layer "B.SilkS")
			(hide yes)
			(effects
				(font
					(size 1.27 1.27)
				)
				(justify mirror)
			)
		)
		(property "Value" "TPAD28-2-GP"
			(at 0.0127 -1.6637 0)
			(unlocked yes)
			(layer "B.Fab")
			(hide yes)
			(effects
				(font
					(size 1.016 1.016)
					(thickness 0.1524)
				)
				(justify mirror)
			)
		)
		(property "Device Type" "TPAD28"
			(at 0.0127 -3.1877 0)
			(unlocked yes)
			(layer "B.Fab")
			(hide yes)
			(effects
				(font
					(size 1.016 1.016)
					(thickness 0.1524)
				)
				(justify mirror)
			)
		)
		(duplicate_pad_numbers_are_jumpers no)
		(fp_poly
			(pts
				(arc
					(start 0.3556 0)
					(mid -0.3556 0)
					(end 0.3556 0)
				)
			)
			(stroke
				(width 0)
				(type default)
			)
			(fill no)
			(layer "B.CrtYd")
		)
		(fp_poly
			(pts
				(arc
					(start 0.6096 0)
					(mid -0.6096 0)
					(end 0.6096 0)
				)
			)
			(stroke
				(width 0)
				(type default)
			)
			(fill no)
			(layer "B.Fab")
		)
		(pad "1" smd circle
			(at 0 0 180)
			(size 0.7112 0.7112)
			(layers "B.Cu" "B.Mask" "B.Paste")
			(net "TP_BMC_GPIOI3")
		)
	)
	(footprint ""
		(layer "B.Cu")
		(at 32.4612 -156.5656 180)
		(property "Reference" "R782"
			(at 0 0 0)
			(layer "B.SilkS")
			(hide yes)
			(effects
				(font
					(size 1.27 1.27)
				)
				(justify mirror)
			)
		)
		(property "Value" "4K7R2F-GP"
			(at -0.064008 -3.993896 180)
			(unlocked yes)
			(layer "B.Fab")
			(hide yes)
			(effects
				(font
					(size 1.016 1.016)
					(thickness 0.1524)
				)
				(justify mirror)
			)
		)
		(property "Device Type" "R402H16"
			(at -0.064008 -5.517896 180)
			(unlocked yes)
			(layer "B.Fab")
			(hide yes)
			(effects
				(font
					(size 1.016 1.016)
					(thickness 0.1524)
				)
				(justify mirror)
			)
		)
		(duplicate_pad_numbers_are_jumpers no)
		(fp_line
			(start 0.508 -0.9398)
			(end 0.508 0.9398)
			(stroke
				(width 0.1524)
				(type default)
			)
			(layer "B.SilkS")
		)
		(fp_line
			(start -0.508 -0.9398)
			(end 0.508 -0.9398)
			(stroke
				(width 0.1524)
				(type default)
			)
			(layer "B.SilkS")
		)
		(fp_rect
			(start 0.508 0.9398)
			(end -0.508 -0.9398)
			(stroke
				(width 0)
				(type default)
			)
			(fill no)
			(layer "B.CrtYd")
		)
		(fp_rect
			(start 0.508 0.9398)
			(end -0.508 -0.9398)
			(stroke
				(width 0)
				(type default)
			)
			(fill no)
			(layer "B.Fab")
		)
		(pad "1" smd custom
			(at 0 -0.4445)
			(size 0.1397 0.1397)
			(layers "B.Cu" "B.Mask" "B.Paste")
			(net "COMP_FAST_THROTTLE_N")
			(options
				(clearance outline)
				(anchor circle)
			)
			(primitives
				(gr_poly
					(pts
						(arc
							(start -0.1778 0.2794)
							(mid -0.249642 0.249642)
							(end -0.2794 0.1778)
						)
						(arc
							(start -0.2794 -0.1778)
							(mid -0.249642 -0.249642)
							(end -0.1778 -0.2794)
						)
						(arc
							(start 0.1778 -0.2794)
							(mid 0.249642 -0.249642)
							(end 0.2794 -0.1778)
						)
						(arc
							(start 0.2794 0.1778)
							(mid 0.249642 0.249642)
							(end 0.1778 0.2794)
						)
					)
					(width 0)
					(fill yes)
				)
			)
		)
		(pad "2" smd custom
			(at 0 0.4445)
			(size 0.1397 0.1397)
			(layers "B.Cu" "B.Mask" "B.Paste")
			(net "GND")
			(options
				(clearance outline)
				(anchor circle)
			)
			(primitives
				(gr_poly
					(pts
						(arc
							(start -0.1778 0.2794)
							(mid -0.249642 0.249642)
							(end -0.2794 0.1778)
						)
						(arc
							(start -0.2794 -0.1778)
							(mid -0.249642 -0.249642)
							(end -0.1778 -0.2794)
						)
						(arc
							(start 0.1778 -0.2794)
							(mid 0.249642 -0.249642)
							(end 0.2794 -0.1778)
						)
						(arc
							(start 0.2794 0.1778)
							(mid 0.249642 0.249642)
							(end 0.1778 0.2794)
						)
					)
					(width 0)
					(fill yes)
				)
			)
		)
	)
	(footprint ""
		(layer "B.Cu")
		(at 175.710596 -73.397618)
		(property "Reference" "TP108"
			(at 0 0 0)
			(layer "B.SilkS")
			(hide yes)
			(effects
				(font
					(size 1.27 1.27)
				)
				(justify mirror)
			)
		)
		(property "Value" "TPAD28-2-GP"
			(at 0.0127 -1.6637 0)
			(unlocked yes)
			(layer "B.Fab")
			(hide yes)
			(effects
				(font
					(size 1.016 1.016)
					(thickness 0.1524)
				)
				(justify mirror)
			)
		)
		(property "Device Type" "TPAD28"
			(at 0.0127 -3.1877 0)
			(unlocked yes)
			(layer "B.Fab")
			(hide yes)
			(effects
				(font
					(size 1.016 1.016)
					(thickness 0.1524)
				)
				(justify mirror)
			)
		)
		(duplicate_pad_numbers_are_jumpers no)
		(fp_poly
			(pts
				(arc
					(start 0.3556 0)
					(mid -0.3556 0)
					(end 0.3556 0)
				)
			)
			(stroke
				(width 0)
				(type default)
			)
			(fill no)
			(layer "B.CrtYd")
		)
		(fp_poly
			(pts
				(arc
					(start 0.6096 0)
					(mid -0.6096 0)
					(end 0.6096 0)
				)
			)
			(stroke
				(width 0)
				(type default)
			)
			(fill no)
			(layer "B.Fab")
		)
		(pad "1" smd circle
			(at 0 0 180)
			(size 0.7112 0.7112)
			(layers "B.Cu" "B.Mask" "B.Paste")
			(net "IOC_GPIO_23")
		)
	)
	(footprint ""
		(layer "B.Cu")
		(at 198.50354 -70.10908 90)
		(property "Reference" "C368"
			(at 0 0 90)
			(layer "B.SilkS")
			(hide yes)
			(effects
				(font
					(size 1.27 1.27)
				)
				(justify mirror)
			)
		)
		(property "Value" "SCD1U6D3V1KX-GP"
			(at 2.8321 -1.7399 90)
			(unlocked yes)
			(layer "B.Fab")
			(hide yes)
			(effects
				(font
					(size 1.016 1.016)
					(thickness 0.1524)
				)
				(justify mirror)
			)
		)
		(property "Device Type" "C0201H13"
			(at 2.8321 -3.2639 90)
			(unlocked yes)
			(layer "B.Fab")
			(hide yes)
			(effects
				(font
					(size 1.016 1.016)
					(thickness 0.1524)
				)
				(justify mirror)
			)
		)
		(duplicate_pad_numbers_are_jumpers no)
		(fp_rect
			(start 0.2794 0.6477)
			(end -0.2794 -0.6477)
			(stroke
				(width 0)
				(type default)
			)
			(fill no)
			(layer "B.CrtYd")
		)
		(fp_rect
			(start 0.2794 0.6477)
			(end -0.2794 -0.6477)
			(stroke
				(width 0)
				(type default)
			)
			(fill no)
			(layer "B.Fab")
		)
		(pad "1" smd custom
			(at 0 -0.2794 270)
			(size 0.0762 0.0762)
			(layers "B.Cu" "B.Mask" "B.Paste")
			(net "PCE_AVDD")
			(options
				(clearance outline)
				(anchor circle)
			)
			(primitives
				(gr_poly
					(pts
						(arc
							(start 0.1524 0.127)
							(mid 0.137521 0.162921)
							(end 0.1016 0.1778)
						)
						(arc
							(start -0.1016 0.1778)
							(mid -0.137521 0.162921)
							(end -0.1524 0.127)
						)
						(arc
							(start -0.1524 -0.127)
							(mid -0.137521 -0.162921)
							(end -0.1016 -0.1778)
						)
						(arc
							(start 0.1016 -0.1778)
							(mid 0.137521 -0.162921)
							(end 0.1524 -0.127)
						)
					)
					(width 0)
					(fill yes)
				)
			)
		)
		(pad "2" smd custom
			(at 0 0.2794 270)
			(size 0.0762 0.0762)
			(layers "B.Cu" "B.Mask" "B.Paste")
			(net "GND")
			(options
				(clearance outline)
				(anchor circle)
			)
			(primitives
				(gr_poly
					(pts
						(arc
							(start 0.1524 0.127)
							(mid 0.137521 0.162921)
							(end 0.1016 0.1778)
						)
						(arc
							(start -0.1016 0.1778)
							(mid -0.137521 0.162921)
							(end -0.1524 0.127)
						)
						(arc
							(start -0.1524 -0.127)
							(mid -0.137521 -0.162921)
							(end -0.1016 -0.1778)
						)
						(arc
							(start 0.1016 -0.1778)
							(mid 0.137521 -0.162921)
							(end 0.1524 -0.127)
						)
					)
					(width 0)
					(fill yes)
				)
			)
		)
	)
	(footprint ""
		(layer "B.Cu")
		(at 188.3791 -58.8772)
		(property "Reference" "C389"
			(at 0 0 0)
			(layer "B.SilkS")
			(hide yes)
			(effects
				(font
					(size 1.27 1.27)
				)
				(justify mirror)
			)
		)
		(property "Value" "SC10U6D3V5KX-4GP"
			(at 0.0762 -6.1214 0)
			(unlocked yes)
			(layer "B.Fab")
			(hide yes)
			(effects
				(font
					(size 1.016 1.016)
					(thickness 0.1524)
				)
				(justify mirror)
			)
		)
		(property "Device Type" "C805H58"
			(at 0.0762 -8.1534 0)
			(unlocked yes)
			(layer "B.Fab")
			(hide yes)
			(effects
				(font
					(size 1.016 1.016)
					(thickness 0.1524)
				)
				(justify mirror)
			)
		)
		(duplicate_pad_numbers_are_jumpers no)
		(fp_line
			(start -0.635 0)
			(end 0.635 0)
			(stroke
				(width 0.508)
				(type default)
			)
			(layer "B.SilkS")
		)
		(fp_rect
			(start 0.9652 1.778)
			(end -0.9652 -1.778)
			(stroke
				(width 0)
				(type default)
			)
			(fill no)
			(layer "B.CrtYd")
		)
		(fp_poly
			(pts
				(xy 0.9652 -1.778) (xy -0.9652 -1.778) (xy -0.9652 1.778) (xy 0.9652 1.778)
			)
			(stroke
				(width 0)
				(type default)
			)
			(fill no)
			(layer "B.Fab")
		)
		(pad "1" smd rect
			(at 0 -0.9652 180)
			(size 1.397 1.143)
			(layers "B.Cu" "B.Mask" "B.Paste")
			(net "P0V975")
		)
		(pad "2" smd rect
			(at 0 0.9652 180)
			(size 1.397 1.143)
			(layers "B.Cu" "B.Mask" "B.Paste")
			(net "GND")
		)
	)
	(footprint ""
		(layer "B.Cu")
		(at 191.008 -72.9234)
		(property "Reference" "C359"
			(at 0 0 0)
			(layer "B.SilkS")
			(hide yes)
			(effects
				(font
					(size 1.27 1.27)
				)
				(justify mirror)
			)
		)
		(property "Value" "SCD1U6D3V1KX-GP"
			(at 2.8321 -1.7399 0)
			(unlocked yes)
			(layer "B.Fab")
			(hide yes)
			(effects
				(font
					(size 1.016 1.016)
					(thickness 0.1524)
				)
				(justify mirror)
			)
		)
		(property "Device Type" "C0201H13"
			(at 2.8321 -3.2639 0)
			(unlocked yes)
			(layer "B.Fab")
			(hide yes)
			(effects
				(font
					(size 1.016 1.016)
					(thickness 0.1524)
				)
				(justify mirror)
			)
		)
		(duplicate_pad_numbers_are_jumpers no)
		(fp_rect
			(start 0.2794 0.6477)
			(end -0.2794 -0.6477)
			(stroke
				(width 0)
				(type default)
			)
			(fill no)
			(layer "B.CrtYd")
		)
		(fp_rect
			(start 0.2794 0.6477)
			(end -0.2794 -0.6477)
			(stroke
				(width 0)
				(type default)
			)
			(fill no)
			(layer "B.Fab")
		)
		(pad "1" smd custom
			(at 0 -0.2794 180)
			(size 0.0762 0.0762)
			(layers "B.Cu" "B.Mask" "B.Paste")
			(net "PCE_VDDH")
			(options
				(clearance outline)
				(anchor circle)
			)
			(primitives
				(gr_poly
					(pts
						(arc
							(start 0.1524 0.127)
							(mid 0.137521 0.162921)
							(end 0.1016 0.1778)
						)
						(arc
							(start -0.1016 0.1778)
							(mid -0.137521 0.162921)
							(end -0.1524 0.127)
						)
						(arc
							(start -0.1524 -0.127)
							(mid -0.137521 -0.162921)
							(end -0.1016 -0.1778)
						)
						(arc
							(start 0.1016 -0.1778)
							(mid 0.137521 -0.162921)
							(end 0.1524 -0.127)
						)
					)
					(width 0)
					(fill yes)
				)
			)
		)
		(pad "2" smd custom
			(at 0 0.2794 180)
			(size 0.0762 0.0762)
			(layers "B.Cu" "B.Mask" "B.Paste")
			(net "GND")
			(options
				(clearance outline)
				(anchor circle)
			)
			(primitives
				(gr_poly
					(pts
						(arc
							(start 0.1524 0.127)
							(mid 0.137521 0.162921)
							(end 0.1016 0.1778)
						)
						(arc
							(start -0.1016 0.1778)
							(mid -0.137521 0.162921)
							(end -0.1524 0.127)
						)
						(arc
							(start -0.1524 -0.127)
							(mid -0.137521 -0.162921)
							(end -0.1016 -0.1778)
						)
						(arc
							(start 0.1016 -0.1778)
							(mid 0.137521 -0.162921)
							(end 0.1524 -0.127)
						)
					)
					(width 0)
					(fill yes)
				)
			)
		)
	)
)
